(kicad_pcb
	(version 20260206)
	(generator "pcbnew")
	(generator_version "10.0")
	(general
		(thickness 1.6)
		(legacy_teardrops no)
	)
	(paper "A4")
	(title_block
		(title "04192023_DAF0TMB3IC0_F0TG_MB_C_brd_V02_OCP.brd")
		(comment 1 "Grand Teton / footprints 7193-7200 of 8354")
	)
	(layers
		(0 "F.Cu" signal "TOP")
		(4 "In1.Cu" signal "GND")
		(6 "In2.Cu" signal "IN1")
		(8 "In3.Cu" signal "GND1")
		(10 "In4.Cu" signal "IN2")
		(12 "In5.Cu" signal "GND2")
		(14 "In6.Cu" signal "IN3")
		(16 "In7.Cu" signal "GND3")
		(18 "In8.Cu" signal "VCC")
		(20 "In9.Cu" signal "VCC1")
		(22 "In10.Cu" signal "GND4")
		(24 "In11.Cu" signal "IN4")
		(26 "In12.Cu" signal "GND5")
		(28 "In13.Cu" signal "IN5")
		(30 "In14.Cu" signal "GND6")
		(32 "In15.Cu" signal "IN6")
		(34 "In16.Cu" signal "GND7")
		(2 "B.Cu" signal "BOTTOM")
		(9 "F.Adhes" user "F.Adhesive")
		(11 "B.Adhes" user "B.Adhesive")
		(13 "F.Paste" user "Package Geometry/Pastemask Top")
		(15 "B.Paste" user "Package Geometry/Pastemask Bottom")
		(5 "F.SilkS" user "Ref Des/Silkscreen Top")
		(7 "B.SilkS" user "Ref Des/Silkscreen Bottom")
		(1 "F.Mask" user "Board Geometry/Soldermask Top")
		(3 "B.Mask" user "Board Geometry/Soldermask Bottom")
		(17 "Dwgs.User" user "User.Drawings")
		(19 "Cmts.User" user "User.Comments")
		(21 "Eco1.User" user "User.Eco1")
		(23 "Eco2.User" user "User.Eco2")
		(25 "Edge.Cuts" user "Board Geometry/Outline")
		(27 "Margin" user)
		(31 "F.CrtYd" user "Package Geometry/Place Bound Top")
		(29 "B.CrtYd" user "Package Geometry/Place Bound Bottom")
		(35 "F.Fab" user "Ref Des/Assembly Top")
		(33 "B.Fab" user "Ref Des/Assembly Bottom")
	)
	(footprint ""
		(layer "B.Cu")
		(at 406.666954 -175.3489 90)
		(property "Reference" "PC598"
			(at 6.709664 -0.521462 270)
			(unlocked yes)
			(layer "B.SilkS")
			(effects
				(font
					(size 0.7874 0.5842)
					(thickness 0.1524)
				)
				(justify left mirror)
			)
		)
		(property "Value" ""
			(at 0 0 90)
			(layer "B.Fab")
			(effects
				(font
					(size 1.27 1.27)
				)
				(justify mirror)
			)
		)
		(duplicate_pad_numbers_are_jumpers no)
		(fp_line
			(start 4.533392 -2.249932)
			(end -4.533392 -2.249932)
			(stroke
				(width 0.1524)
				(type default)
			)
			(layer "B.SilkS")
		)
		(fp_line
			(start -4.533392 -2.249932)
			(end -4.533392 2.249932)
			(stroke
				(width 0.1524)
				(type default)
			)
			(layer "B.SilkS")
		)
		(fp_line
			(start 4.533392 2.249932)
			(end 4.533392 -2.249932)
			(stroke
				(width 0.1524)
				(type default)
			)
			(layer "B.SilkS")
		)
		(fp_line
			(start -4.533392 2.249932)
			(end 4.533392 2.249932)
			(stroke
				(width 0.1524)
				(type default)
			)
			(layer "B.SilkS")
		)
		(fp_rect
			(start 4.533392 -2.326132)
			(end 5.39242 2.326132)
			(stroke
				(width 0)
				(type default)
			)
			(fill yes)
			(layer "B.SilkS")
		)
		(fp_line
			(start 3.750056 -2.249932)
			(end -3.750056 -2.249932)
			(stroke
				(width 0.1)
				(type default)
			)
			(layer "B.Fab")
		)
		(fp_line
			(start -3.750056 -2.249932)
			(end -3.750056 2.249932)
			(stroke
				(width 0.1)
				(type default)
			)
			(layer "B.Fab")
		)
		(fp_line
			(start 3.750056 2.249932)
			(end 3.750056 -2.249932)
			(stroke
				(width 0.1)
				(type default)
			)
			(layer "B.Fab")
		)
		(fp_line
			(start -3.750056 2.249932)
			(end 3.750056 2.249932)
			(stroke
				(width 0.1)
				(type default)
			)
			(layer "B.Fab")
		)
		(fp_text user "+"
			(at 6.322314 0.786384 0)
			(unlocked yes)
			(layer "B.SilkS")
			(effects
				(font
					(size 1.905 1.4224)
					(thickness 0.1524)
				)
				(justify left mirror)
			)
		)
		(fp_text user "-"
			(at -4.060698 2.725674 90)
			(unlocked yes)
			(layer "B.SilkS")
			(effects
				(font
					(size 1.905 1.4224)
					(thickness 0.1524)
				)
				(justify left mirror)
			)
		)
		(fp_text user "-"
			(at -4.8514 -0.14605 90)
			(unlocked yes)
			(layer "B.Fab")
			(effects
				(font
					(size 1.905 1.4224)
					(thickness 0.1524)
				)
				(justify left mirror)
			)
		)
		(fp_text user "+"
			(at 6.322314 0.786384 0)
			(unlocked yes)
			(layer "B.Fab")
			(effects
				(font
					(size 1.905 1.4224)
					(thickness 0.1524)
				)
				(justify left mirror)
			)
		)
		(pad "1" smd rect
			(at 3.199892 0 270)
			(size 2.413 2.8194)
			(layers "B.Cu" "B.Mask" "B.Paste")
			(net "PVDDCR_SOC_P0")
		)
		(pad "2" smd rect
			(at -3.199892 0 270)
			(size 2.413 2.8194)
			(layers "B.Cu" "B.Mask" "B.Paste")
			(net "GND")
		)
	)
	(footprint ""
		(layer "B.Cu")
		(at 238.310928 -290.844732 180)
		(property "Reference" "R6505"
			(at 0 0 0)
			(layer "B.SilkS")
			(hide yes)
			(effects
				(font
					(size 1.27 1.27)
				)
				(justify mirror)
			)
		)
		(property "Value" ""
			(at 0 0 0)
			(layer "B.Fab")
			(effects
				(font
					(size 1.27 1.27)
				)
				(justify mirror)
			)
		)
		(duplicate_pad_numbers_are_jumpers no)
		(fp_line
			(start 0.7874 0.4064)
			(end 0.7874 -0.4064)
			(stroke
				(width 0.1524)
				(type default)
			)
			(layer "B.SilkS")
		)
		(fp_line
			(start 0.7874 -0.4064)
			(end -0.7874 -0.4064)
			(stroke
				(width 0.1524)
				(type default)
			)
			(layer "B.SilkS")
		)
		(fp_line
			(start -0.7874 0.4064)
			(end 0.7874 0.4064)
			(stroke
				(width 0.1524)
				(type default)
			)
			(layer "B.SilkS")
		)
		(fp_line
			(start -0.7874 -0.4064)
			(end -0.7874 0.4064)
			(stroke
				(width 0.1524)
				(type default)
			)
			(layer "B.SilkS")
		)
		(fp_line
			(start 0.67945 0.3048)
			(end 0.67945 -0.305054)
			(stroke
				(width 0.1)
				(type default)
			)
			(layer "B.Fab")
		)
		(fp_line
			(start 0.67945 -0.305054)
			(end 0.12065 -0.305054)
			(stroke
				(width 0.1)
				(type default)
			)
			(layer "B.Fab")
		)
		(fp_line
			(start 0.12065 0.3048)
			(end 0.67945 0.3048)
			(stroke
				(width 0.1)
				(type default)
			)
			(layer "B.Fab")
		)
		(fp_line
			(start 0.12065 0.2794)
			(end 0.12065 0.3048)
			(stroke
				(width 0.1)
				(type default)
			)
			(layer "B.Fab")
		)
		(fp_line
			(start 0.12065 -0.2794)
			(end -0.12065 -0.2794)
			(stroke
				(width 0.1)
				(type default)
			)
			(layer "B.Fab")
		)
		(fp_line
			(start 0.12065 -0.305054)
			(end 0.12065 -0.2794)
			(stroke
				(width 0.1)
				(type default)
			)
			(layer "B.Fab")
		)
		(fp_line
			(start -0.120396 0.3048)
			(end -0.120396 0.2794)
			(stroke
				(width 0.1)
				(type default)
			)
			(layer "B.Fab")
		)
		(fp_line
			(start -0.120396 0.2794)
			(end 0.12065 0.2794)
			(stroke
				(width 0.1)
				(type default)
			)
			(layer "B.Fab")
		)
		(fp_line
			(start -0.12065 -0.2794)
			(end -0.12065 -0.3048)
			(stroke
				(width 0.1)
				(type default)
			)
			(layer "B.Fab")
		)
		(fp_line
			(start -0.12065 -0.3048)
			(end -0.67945 -0.3048)
			(stroke
				(width 0.1)
				(type default)
			)
			(layer "B.Fab")
		)
		(fp_line
			(start -0.67945 0.3048)
			(end -0.120396 0.3048)
			(stroke
				(width 0.1)
				(type default)
			)
			(layer "B.Fab")
		)
		(fp_line
			(start -0.67945 -0.3048)
			(end -0.67945 0.3048)
			(stroke
				(width 0.1)
				(type default)
			)
			(layer "B.Fab")
		)
		(pad "1" smd circle
			(at 0.40005 0)
			(size 0 0)
			(layers "B.Cu" "B.Mask" "B.Paste")
			(net "P3V3_AUX")
		)
		(pad "2" smd circle
			(at -0.40005 0)
			(size 0 0)
			(layers "B.Cu" "B.Mask" "B.Paste")
			(net "PWRGD_P1V8_RETIMER_CPU0")
		)
	)
	(footprint ""
		(layer "B.Cu")
		(at 137.74547 -387.084062 -90)
		(property "Reference" "C432"
			(at 0 0 90)
			(layer "B.SilkS")
			(hide yes)
			(effects
				(font
					(size 1.27 1.27)
				)
				(justify mirror)
			)
		)
		(property "Value" ""
			(at 0 0 90)
			(layer "B.Fab")
			(effects
				(font
					(size 1.27 1.27)
				)
				(justify mirror)
			)
		)
		(duplicate_pad_numbers_are_jumpers no)
		(fp_line
			(start -1.524 0.762)
			(end 1.524 0.762)
			(stroke
				(width 0.1524)
				(type default)
			)
			(layer "B.SilkS")
		)
		(fp_line
			(start 1.524 0.762)
			(end 1.524 -0.762)
			(stroke
				(width 0.1524)
				(type default)
			)
			(layer "B.SilkS")
		)
		(fp_line
			(start -1.524 -0.762)
			(end -1.524 0.762)
			(stroke
				(width 0.1524)
				(type default)
			)
			(layer "B.SilkS")
		)
		(fp_line
			(start 1.524 -0.762)
			(end -1.524 -0.762)
			(stroke
				(width 0.1524)
				(type default)
			)
			(layer "B.SilkS")
		)
		(fp_line
			(start -1.1049 0.724916)
			(end -1.1049 -0.724916)
			(stroke
				(width 0.1)
				(type default)
			)
			(layer "B.Fab")
		)
		(fp_line
			(start 1.1049 0.724916)
			(end -1.1049 0.724916)
			(stroke
				(width 0.1)
				(type default)
			)
			(layer "B.Fab")
		)
		(fp_line
			(start -1.1049 -0.724916)
			(end 1.1049 -0.724916)
			(stroke
				(width 0.1)
				(type default)
			)
			(layer "B.Fab")
		)
		(fp_line
			(start 1.1049 -0.724916)
			(end 1.1049 0.724916)
			(stroke
				(width 0.1)
				(type default)
			)
			(layer "B.Fab")
		)
		(pad "1" smd rect
			(at 0.889 0 270)
			(size 1.016 1.27)
			(layers "B.Cu" "B.Mask" "B.Paste")
			(net "P1V8_CPU1_RT_1D")
		)
		(pad "2" smd rect
			(at -0.889 0 270)
			(size 1.016 1.27)
			(layers "B.Cu" "B.Mask" "B.Paste")
			(net "GND")
		)
	)
	(footprint ""
		(layer "B.Cu")
		(at 59.391296 -390.909302 90)
		(property "Reference" "C185"
			(at 0 0 90)
			(layer "B.SilkS")
			(hide yes)
			(effects
				(font
					(size 1.27 1.27)
				)
				(justify mirror)
			)
		)
		(property "Value" ""
			(at 0 0 90)
			(layer "B.Fab")
			(effects
				(font
					(size 1.27 1.27)
				)
				(justify mirror)
			)
		)
		(duplicate_pad_numbers_are_jumpers no)
		(fp_line
			(start 0.299974 -0.150114)
			(end -0.299974 -0.150114)
			(stroke
				(width 0.1)
				(type default)
			)
			(layer "B.Fab")
		)
		(fp_line
			(start -0.299974 -0.150114)
			(end -0.299974 0.150114)
			(stroke
				(width 0.1)
				(type default)
			)
			(layer "B.Fab")
		)
		(fp_line
			(start 0.299974 0.150114)
			(end 0.299974 -0.150114)
			(stroke
				(width 0.1)
				(type default)
			)
			(layer "B.Fab")
		)
		(fp_line
			(start -0.299974 0.150114)
			(end 0.299974 0.150114)
			(stroke
				(width 0.1)
				(type default)
			)
			(layer "B.Fab")
		)
		(pad "1" smd rect
			(at 0.2667 0 270)
			(size 0.3048 0.381)
			(layers "B.Cu" "B.Mask" "B.Paste")
			(net "P0V9_CPU1_RT_2D")
		)
		(pad "2" smd rect
			(at -0.2667 0 270)
			(size 0.3048 0.381)
			(layers "B.Cu" "B.Mask" "B.Paste")
			(net "GND")
		)
	)
	(footprint ""
		(layer "B.Cu")
		(at 428.98695 -30.165548 180)
		(property "Reference" "R6041"
			(at 0 0 0)
			(layer "B.SilkS")
			(hide yes)
			(effects
				(font
					(size 1.27 1.27)
				)
				(justify mirror)
			)
		)
		(property "Value" ""
			(at 0 0 0)
			(layer "B.Fab")
			(effects
				(font
					(size 1.27 1.27)
				)
				(justify mirror)
			)
		)
		(duplicate_pad_numbers_are_jumpers no)
		(fp_line
			(start 0.7874 0.4064)
			(end 0.7874 -0.4064)
			(stroke
				(width 0.1524)
				(type default)
			)
			(layer "B.SilkS")
		)
		(fp_line
			(start 0.7874 -0.4064)
			(end -0.7874 -0.4064)
			(stroke
				(width 0.1524)
				(type default)
			)
			(layer "B.SilkS")
		)
		(fp_line
			(start -0.7874 0.4064)
			(end 0.7874 0.4064)
			(stroke
				(width 0.1524)
				(type default)
			)
			(layer "B.SilkS")
		)
		(fp_line
			(start -0.7874 -0.4064)
			(end -0.7874 0.4064)
			(stroke
				(width 0.1524)
				(type default)
			)
			(layer "B.SilkS")
		)
		(fp_line
			(start 0.67945 0.3048)
			(end 0.67945 -0.305054)
			(stroke
				(width 0.1)
				(type default)
			)
			(layer "B.Fab")
		)
		(fp_line
			(start 0.67945 -0.305054)
			(end 0.12065 -0.305054)
			(stroke
				(width 0.1)
				(type default)
			)
			(layer "B.Fab")
		)
		(fp_line
			(start 0.12065 0.3048)
			(end 0.67945 0.3048)
			(stroke
				(width 0.1)
				(type default)
			)
			(layer "B.Fab")
		)
		(fp_line
			(start 0.12065 0.2794)
			(end 0.12065 0.3048)
			(stroke
				(width 0.1)
				(type default)
			)
			(layer "B.Fab")
		)
		(fp_line
			(start 0.12065 -0.2794)
			(end -0.12065 -0.2794)
			(stroke
				(width 0.1)
				(type default)
			)
			(layer "B.Fab")
		)
		(fp_line
			(start 0.12065 -0.305054)
			(end 0.12065 -0.2794)
			(stroke
				(width 0.1)
				(type default)
			)
			(layer "B.Fab")
		)
		(fp_line
			(start -0.120396 0.3048)
			(end -0.120396 0.2794)
			(stroke
				(width 0.1)
				(type default)
			)
			(layer "B.Fab")
		)
		(fp_line
			(start -0.120396 0.2794)
			(end 0.12065 0.2794)
			(stroke
				(width 0.1)
				(type default)
			)
			(layer "B.Fab")
		)
		(fp_line
			(start -0.12065 -0.2794)
			(end -0.12065 -0.3048)
			(stroke
				(width 0.1)
				(type default)
			)
			(layer "B.Fab")
		)
		(fp_line
			(start -0.12065 -0.3048)
			(end -0.67945 -0.3048)
			(stroke
				(width 0.1)
				(type default)
			)
			(layer "B.Fab")
		)
		(fp_line
			(start -0.67945 0.3048)
			(end -0.120396 0.3048)
			(stroke
				(width 0.1)
				(type default)
			)
			(layer "B.Fab")
		)
		(fp_line
			(start -0.67945 -0.3048)
			(end -0.67945 0.3048)
			(stroke
				(width 0.1)
				(type default)
			)
			(layer "B.Fab")
		)
		(pad "1" smd circle
			(at 0.40005 0)
			(size 0 0)
			(layers "B.Cu" "B.Mask" "B.Paste")
			(net "GND")
		)
		(pad "2" smd circle
			(at -0.40005 0)
			(size 0 0)
			(layers "B.Cu" "B.Mask" "B.Paste")
			(net "FPGA_DEBUG_LED_CTRL")
		)
	)
	(footprint ""
		(layer "B.Cu")
		(at 163.359084 -9.013444 -90)
		(property "Reference" "R2205"
			(at 0 0 90)
			(layer "B.SilkS")
			(hide yes)
			(effects
				(font
					(size 1.27 1.27)
				)
				(justify mirror)
			)
		)
		(property "Value" ""
			(at 0 0 90)
			(layer "B.Fab")
			(effects
				(font
					(size 1.27 1.27)
				)
				(justify mirror)
			)
		)
		(duplicate_pad_numbers_are_jumpers no)
		(fp_line
			(start -0.7874 0.4064)
			(end 0.7874 0.4064)
			(stroke
				(width 0.1524)
				(type default)
			)
			(layer "B.SilkS")
		)
		(fp_line
			(start 0.7874 0.4064)
			(end 0.7874 -0.4064)
			(stroke
				(width 0.1524)
				(type default)
			)
			(layer "B.SilkS")
		)
		(fp_line
			(start -0.7874 -0.4064)
			(end -0.7874 0.4064)
			(stroke
				(width 0.1524)
				(type default)
			)
			(layer "B.SilkS")
		)
		(fp_line
			(start 0.7874 -0.4064)
			(end -0.7874 -0.4064)
			(stroke
				(width 0.1524)
				(type default)
			)
			(layer "B.SilkS")
		)
		(fp_line
			(start -0.67945 0.3048)
			(end -0.120396 0.3048)
			(stroke
				(width 0.1)
				(type default)
			)
			(layer "B.Fab")
		)
		(fp_line
			(start -0.120396 0.3048)
			(end -0.120396 0.2794)
			(stroke
				(width 0.1)
				(type default)
			)
			(layer "B.Fab")
		)
		(fp_line
			(start 0.12065 0.3048)
			(end 0.67945 0.3048)
			(stroke
				(width 0.1)
				(type default)
			)
			(layer "B.Fab")
		)
		(fp_line
			(start 0.67945 0.3048)
			(end 0.67945 -0.305054)
			(stroke
				(width 0.1)
				(type default)
			)
			(layer "B.Fab")
		)
		(fp_line
			(start -0.120396 0.2794)
			(end 0.12065 0.2794)
			(stroke
				(width 0.1)
				(type default)
			)
			(layer "B.Fab")
		)
		(fp_line
			(start 0.12065 0.2794)
			(end 0.12065 0.3048)
			(stroke
				(width 0.1)
				(type default)
			)
			(layer "B.Fab")
		)
		(fp_line
			(start -0.12065 -0.2794)
			(end -0.12065 -0.3048)
			(stroke
				(width 0.1)
				(type default)
			)
			(layer "B.Fab")
		)
		(fp_line
			(start 0.12065 -0.2794)
			(end -0.12065 -0.2794)
			(stroke
				(width 0.1)
				(type default)
			)
			(layer "B.Fab")
		)
		(fp_line
			(start -0.67945 -0.3048)
			(end -0.67945 0.3048)
			(stroke
				(width 0.1)
				(type default)
			)
			(layer "B.Fab")
		)
		(fp_line
			(start -0.12065 -0.3048)
			(end -0.67945 -0.3048)
			(stroke
				(width 0.1)
				(type default)
			)
			(layer "B.Fab")
		)
		(fp_line
			(start 0.12065 -0.305054)
			(end 0.12065 -0.2794)
			(stroke
				(width 0.1)
				(type default)
			)
			(layer "B.Fab")
		)
		(fp_line
			(start 0.67945 -0.305054)
			(end 0.12065 -0.305054)
			(stroke
				(width 0.1)
				(type default)
			)
			(layer "B.Fab")
		)
		(pad "1" smd circle
			(at 0.40005 0 90)
			(size 0 0)
			(layers "B.Cu" "B.Mask" "B.Paste")
			(net "P3V3_AUX")
		)
		(pad "2" smd circle
			(at -0.40005 0 90)
			(size 0 0)
			(layers "B.Cu" "B.Mask" "B.Paste")
			(net "SMB_PCIE0_3V3AUX_SDA")
		)
	)
	(footprint ""
		(layer "B.Cu")
		(at 179.27701 -421.374824 90)
		(property "Reference" "C6084"
			(at 0 0 90)
			(layer "B.SilkS")
			(hide yes)
			(effects
				(font
					(size 1.27 1.27)
				)
				(justify mirror)
			)
		)
		(property "Value" ""
			(at 0 0 90)
			(layer "B.Fab")
			(effects
				(font
					(size 1.27 1.27)
				)
				(justify mirror)
			)
		)
		(duplicate_pad_numbers_are_jumpers no)
		(fp_line
			(start 0.7874 -0.4064)
			(end -0.7874 -0.4064)
			(stroke
				(width 0.1524)
				(type default)
			)
			(layer "B.SilkS")
		)
		(fp_line
			(start -0.7874 -0.4064)
			(end -0.7874 0.4064)
			(stroke
				(width 0.1524)
				(type default)
			)
			(layer "B.SilkS")
		)
		(fp_line
			(start 0.7874 0.4064)
			(end 0.7874 -0.4064)
			(stroke
				(width 0.1524)
				(type default)
			)
			(layer "B.SilkS")
		)
		(fp_line
			(start -0.7874 0.4064)
			(end 0.7874 0.4064)
			(stroke
				(width 0.1524)
				(type default)
			)
			(layer "B.SilkS")
		)
		(fp_line
			(start 0.67945 -0.305054)
			(end 0.12065 -0.305054)
			(stroke
				(width 0.1)
				(type default)
			)
			(layer "B.Fab")
		)
		(fp_line
			(start 0.12065 -0.305054)
			(end 0.12065 -0.2794)
			(stroke
				(width 0.1)
				(type default)
			)
			(layer "B.Fab")
		)
		(fp_line
			(start -0.12065 -0.3048)
			(end -0.67945 -0.3048)
			(stroke
				(width 0.1)
				(type default)
			)
			(layer "B.Fab")
		)
		(fp_line
			(start -0.67945 -0.3048)
			(end -0.67945 0.3048)
			(stroke
				(width 0.1)
				(type default)
			)
			(layer "B.Fab")
		)
		(fp_line
			(start 0.12065 -0.2794)
			(end -0.12065 -0.2794)
			(stroke
				(width 0.1)
				(type default)
			)
			(layer "B.Fab")
		)
		(fp_line
			(start -0.12065 -0.2794)
			(end -0.12065 -0.3048)
			(stroke
				(width 0.1)
				(type default)
			)
			(layer "B.Fab")
		)
		(fp_line
			(start 0.12065 0.2794)
			(end 0.12065 0.3048)
			(stroke
				(width 0.1)
				(type default)
			)
			(layer "B.Fab")
		)
		(fp_line
			(start -0.120396 0.2794)
			(end 0.12065 0.2794)
			(stroke
				(width 0.1)
				(type default)
			)
			(layer "B.Fab")
		)
		(fp_line
			(start 0.67945 0.3048)
			(end 0.67945 -0.305054)
			(stroke
				(width 0.1)
				(type default)
			)
			(layer "B.Fab")
		)
		(fp_line
			(start 0.12065 0.3048)
			(end 0.67945 0.3048)
			(stroke
				(width 0.1)
				(type default)
			)
			(layer "B.Fab")
		)
		(fp_line
			(start -0.120396 0.3048)
			(end -0.120396 0.2794)
			(stroke
				(width 0.1)
				(type default)
			)
			(layer "B.Fab")
		)
		(fp_line
			(start -0.67945 0.3048)
			(end -0.120396 0.3048)
			(stroke
				(width 0.1)
				(type default)
			)
			(layer "B.Fab")
		)
		(pad "1" smd circle
			(at 0.40005 0 270)
			(size 0 0)
			(layers "B.Cu" "B.Mask" "B.Paste")
			(net "U142_VS")
		)
		(pad "2" smd circle
			(at -0.40005 0 270)
			(size 0 0)
			(layers "B.Cu" "B.Mask" "B.Paste")
			(net "GND")
		)
	)
	(footprint ""
		(layer "B.Cu")
		(at 80.847184 -408.517344 90)
		(property "Reference" "C6681"
			(at 0 0 90)
			(layer "B.SilkS")
			(hide yes)
			(effects
				(font
					(size 1.27 1.27)
				)
				(justify mirror)
			)
		)
		(property "Value" ""
			(at 0 0 90)
			(layer "B.Fab")
			(effects
				(font
					(size 1.27 1.27)
				)
				(justify mirror)
			)
		)
		(duplicate_pad_numbers_are_jumpers no)
		(fp_line
			(start 0.299974 -0.150114)
			(end -0.299974 -0.150114)
			(stroke
				(width 0.1)
				(type default)
			)
			(layer "B.Fab")
		)
		(fp_line
			(start -0.299974 -0.150114)
			(end -0.299974 0.150114)
			(stroke
				(width 0.1)
				(type default)
			)
			(layer "B.Fab")
		)
		(fp_line
			(start 0.299974 0.150114)
			(end 0.299974 -0.150114)
			(stroke
				(width 0.1)
				(type default)
			)
			(layer "B.Fab")
		)
		(fp_line
			(start -0.299974 0.150114)
			(end 0.299974 0.150114)
			(stroke
				(width 0.1)
				(type default)
			)
			(layer "B.Fab")
		)
		(pad "1" smd rect
			(at 0.2667 0 270)
			(size 0.3048 0.381)
			(layers "B.Cu" "B.Mask" "B.Paste")
			(net "P5E_CPU1_P1_TX_BUF_C_DP<10>")
		)
		(pad "2" smd rect
			(at -0.2667 0 270)
			(size 0.3048 0.381)
			(layers "B.Cu" "B.Mask" "B.Paste")
			(net "P5E_CPU1_P1_TX_BUF_DP<10>")
		)
	)
)
